FILE_TYPE = MACRO_DRAWING;
SET COLOR_WIRE YELLOW;
SET COLOR_PROP ORANGE;
SET COLOR_DOT WHITE;
SET COLOR_ARC YELLOW;
SET COLOR_BODY GREEN;
SET COLOR_NOTE PURPLE;
SET PROP_DISPLAY VALUE;
SET PAGE_NUMBER P463;
FORCEADD VCC_CORE..1
(-4675 5050);
FORCEPROP 3 LASTPIN (-4675 5000) SIG_NAME P0V9_CPU1_RT3_2A\g
J 0
(-4665 5010);
DISPLAY 0.659574 (-4665 5010);
PAINT MONO (-4665 5010);
DISPLAY INVISIBLE (-4665 5010);
FORCEPROP 1 LAST HDL_POWER P0V9_CPU1_RT3_2A
J 1
(-4675 5100);
DISPLAY 0.617021 (-4675 5100);
FORCEPROP 2 LAST CDS_LIB pure_quanta_power
J 0
(-4675 5050);
DISPLAY INVISIBLE (-4675 5050);
FORCEPROP 1 LAST PATH I10
J 0
(-4625 5075);
DISPLAY 0.872340 (-4625 5075);
PAINT AQUA (-4625 5075);
DISPLAY INVISIBLE (-4625 5075);
FORCEADD UNIVERSAL_GND..1
(-3125 1350);
FORCEPROP 3 LASTPIN (-3125 1400) SIG_NAME GND\g
J 0
(-3115 1410);
DISPLAY 0.659574 (-3115 1410);
PAINT MONO (-3115 1410);
DISPLAY INVISIBLE (-3115 1410);
FORCEPROP 2 LAST CDS_LIB pure_quanta_power
J 0
(-3125 1350);
DISPLAY INVISIBLE (-3125 1350);
FORCEPROP 1 LAST HDL_POWER GND
J 1
(-3100 1275);
DISPLAY 0.872340 (-3100 1275);
PAINT GREEN (-3100 1275);
DISPLAY INVISIBLE (-3100 1275);
FORCEPROP 1 LAST PATH I11
J 0
(-3050 1350);
DISPLAY 0.872340 (-3050 1350);
PAINT AQUA (-3050 1350);
DISPLAY INVISIBLE (-3050 1350);
FORCEADD UNIVERSAL_GND..1
(-1450 975);
FORCEPROP 3 LASTPIN (-1450 1025) SIG_NAME GND\g
J 0
(-1440 1035);
DISPLAY 0.659574 (-1440 1035);
PAINT MONO (-1440 1035);
DISPLAY INVISIBLE (-1440 1035);
FORCEPROP 2 LAST CDS_LIB pure_quanta_power
J 0
(-1450 975);
DISPLAY INVISIBLE (-1450 975);
FORCEPROP 1 LAST HDL_POWER GND
J 1
(-1425 900);
DISPLAY 0.872340 (-1425 900);
PAINT GREEN (-1425 900);
DISPLAY INVISIBLE (-1425 900);
FORCEPROP 1 LAST PATH I12
J 0
(-1375 975);
DISPLAY 0.872340 (-1375 975);
PAINT AQUA (-1375 975);
DISPLAY INVISIBLE (-1375 975);
FORCEADD Q_RES..2
(-1450 1275);
FORCEPROP 1 LAST LOCATION R6903
J 0
(-1405 1400);
DISPLAY 0.978723 (-1405 1400);
FORCEPROP 0 LAST $SEC 1
J 0
(-1400 1450);
DISPLAY 0.680851 (-1400 1450);
PAINT MONO (-1400 1450);
DISPLAY INVISIBLE (-1400 1450);
FORCEPROP 0 LAST CDS_SEC 1
J 0
(-1400 1450);
DISPLAY 0.680851 (-1400 1450);
DISPLAY INVISIBLE (-1400 1450);
FORCEPROP 1 LASTPIN (-1450 1375) $PN 1
J 0
(-1445 1337);
DISPLAY 0.787234 (-1445 1337);
PAINT MONO (-1445 1337);
FORCEPROP 1 LASTPIN (-1450 1175) $PN 2
J 0
(-1445 1185);
DISPLAY 0.787234 (-1445 1185);
PAINT MONO (-1445 1185);
FORCEPROP 1 LAST MATERIAL CHIP
J 0
(-1410 1200);
DISPLAY 0.978723 (-1410 1200);
FORCEPROP 1 LAST PACK_TYPE 0201LF
J 0
(-1410 1100);
DISPLAY 0.978723 (-1410 1100);
FORCEPROP 1 LAST TOLERANCE 5%
J 0
(-1405 1300);
DISPLAY 0.978723 (-1405 1300);
FORCEPROP 1 LAST WATTAGE 1/20W
J 0
(-1410 1250);
DISPLAY 0.978723 (-1410 1250);
FORCEPROP 1 LAST VALUE 0
J 0
(-1405 1350);
DISPLAY 0.978723 (-1405 1350);
FORCEPROP 2 LAST CDS_LIB pure_quanta
J 0
(-1450 1275);
DISPLAY INVISIBLE (-1450 1275);
FORCEPROP 1 LAST PATH I13
J 0
(-1400 1450);
DISPLAY 0.978723 (-1400 1450);
PAINT WHITE (-1400 1450);
DISPLAY INVISIBLE (-1400 1450);
FORCEPROP 1 LAST PART_NUMBER CS00001JE10
J 0
(-1410 1150);
DISPLAY 0.978723 (-1410 1150);
DISPLAY INVISIBLE (-1410 1150);
FORCEADD UNIVERSAL_GND..1
(-1300 1525);
FORCEPROP 3 LASTPIN (-1300 1575) SIG_NAME GND\g
J 0
(-1290 1585);
DISPLAY 0.659574 (-1290 1585);
PAINT MONO (-1290 1585);
DISPLAY INVISIBLE (-1290 1585);
FORCEPROP 2 LAST CDS_LIB pure_quanta_power
J 0
(-1300 1525);
DISPLAY INVISIBLE (-1300 1525);
FORCEPROP 1 LAST HDL_POWER GND
J 1
(-1275 1450);
DISPLAY 0.872340 (-1275 1450);
PAINT GREEN (-1275 1450);
DISPLAY INVISIBLE (-1275 1450);
FORCEPROP 1 LAST PATH I14
J 0
(-1225 1525);
DISPLAY 0.872340 (-1225 1525);
PAINT AQUA (-1225 1525);
DISPLAY INVISIBLE (-1225 1525);
FORCEADD Q_RES..2
(-1300 1825);
FORCEPROP 1 LAST LOCATION R6902
J 0
(-1255 1950);
DISPLAY 0.978723 (-1255 1950);
FORCEPROP 0 LAST $SEC 1
J 0
(-1250 2000);
DISPLAY 0.680851 (-1250 2000);
PAINT MONO (-1250 2000);
DISPLAY INVISIBLE (-1250 2000);
FORCEPROP 0 LAST CDS_SEC 1
J 0
(-1250 2000);
DISPLAY 0.680851 (-1250 2000);
DISPLAY INVISIBLE (-1250 2000);
FORCEPROP 1 LASTPIN (-1300 1925) $PN 1
J 0
(-1295 1887);
DISPLAY 0.787234 (-1295 1887);
PAINT MONO (-1295 1887);
FORCEPROP 1 LASTPIN (-1300 1725) $PN 2
J 0
(-1295 1735);
DISPLAY 0.787234 (-1295 1735);
PAINT MONO (-1295 1735);
FORCEPROP 1 LAST VALUE 0
J 0
(-1255 1900);
DISPLAY 0.978723 (-1255 1900);
FORCEPROP 1 LAST TOLERANCE 5%
J 0
(-1255 1850);
DISPLAY 0.978723 (-1255 1850);
FORCEPROP 1 LAST MATERIAL CHIP
J 0
(-1260 1750);
DISPLAY 0.978723 (-1260 1750);
FORCEPROP 1 LAST PACK_TYPE 0201LF
J 0
(-1260 1650);
DISPLAY 0.978723 (-1260 1650);
FORCEPROP 1 LAST WATTAGE 1/20W
J 0
(-1260 1800);
DISPLAY 0.978723 (-1260 1800);
FORCEPROP 2 LAST CDS_LIB pure_quanta
J 0
(-1300 1825);
DISPLAY INVISIBLE (-1300 1825);
FORCEPROP 1 LAST PATH I15
J 0
(-1250 2000);
DISPLAY 0.978723 (-1250 2000);
PAINT WHITE (-1250 2000);
DISPLAY INVISIBLE (-1250 2000);
FORCEPROP 1 LAST PART_NUMBER CS00001JE10
J 0
(-1260 1700);
DISPLAY 0.978723 (-1260 1700);
DISPLAY INVISIBLE (-1260 1700);
FORCEADD UNIVERSAL_GND..1
(-1075 2075);
FORCEPROP 3 LASTPIN (-1075 2125) SIG_NAME GND\g
J 0
(-1065 2135);
DISPLAY 0.659574 (-1065 2135);
PAINT MONO (-1065 2135);
DISPLAY INVISIBLE (-1065 2135);
FORCEPROP 2 LAST CDS_LIB pure_quanta_power
J 0
(-1075 2075);
DISPLAY INVISIBLE (-1075 2075);
FORCEPROP 1 LAST HDL_POWER GND
J 1
(-1050 2000);
DISPLAY 0.872340 (-1050 2000);
PAINT GREEN (-1050 2000);
DISPLAY INVISIBLE (-1050 2000);
FORCEPROP 1 LAST PATH I16
J 0
(-1000 2075);
DISPLAY 0.872340 (-1000 2075);
PAINT AQUA (-1000 2075);
DISPLAY INVISIBLE (-1000 2075);
FORCEADD PT5161LRS..5
(-2425 3600);
FORCEPROP 1 LAST LOCATION U6017
J 0
(-2775 5925);
DISPLAY 0.723404 (-2775 5925);
PAINT GREEN (-2775 5925);
FORCEPROP 0 LAST $SEC 5
J 0
(-2775 6075);
DISPLAY 0.680851 (-2775 6075);
PAINT MONO (-2775 6075);
DISPLAY INVISIBLE (-2775 6075);
FORCEPROP 0 LAST CDS_SEC 5
J 0
(-2775 6075);
DISPLAY 0.680851 (-2775 6075);
DISPLAY INVISIBLE (-2775 6075);
FORCEPROP 0 LASTPIN (-2925 5600) $PN AC13
J 2
(-2935 5610);
DISPLAY 0.680851 (-2935 5610);
PAINT MONO (-2935 5610);
FORCEPROP 0 LASTPIN (-2925 5550) $PN AC22
J 2
(-2935 5560);
DISPLAY 0.680851 (-2935 5560);
PAINT MONO (-2935 5560);
FORCEPROP 0 LASTPIN (-2925 5500) $PN AC32
J 2
(-2935 5510);
DISPLAY 0.680851 (-2935 5510);
PAINT MONO (-2935 5510);
FORCEPROP 0 LASTPIN (-2925 5450) $PN AC4
J 2
(-2935 5460);
DISPLAY 0.680851 (-2935 5460);
PAINT MONO (-2935 5460);
FORCEPROP 0 LASTPIN (-2925 5400) $PN AD2
J 2
(-2935 5410);
DISPLAY 0.680851 (-2935 5410);
PAINT MONO (-2935 5410);
FORCEPROP 0 LASTPIN (-2925 5350) $PN AD34
J 2
(-2935 5360);
DISPLAY 0.680851 (-2935 5360);
PAINT MONO (-2935 5360);
FORCEPROP 0 LASTPIN (-2925 5300) $PN AE1
J 2
(-2935 5310);
DISPLAY 0.680851 (-2935 5310);
PAINT MONO (-2935 5310);
FORCEPROP 0 LASTPIN (-2925 5250) $PN AE35
J 2
(-2935 5260);
DISPLAY 0.680851 (-2935 5260);
PAINT MONO (-2935 5260);
FORCEPROP 0 LASTPIN (-2925 5200) $PN AK13
J 2
(-2935 5210);
DISPLAY 0.680851 (-2935 5210);
PAINT MONO (-2935 5210);
FORCEPROP 0 LASTPIN (-2925 5150) $PN AK22
J 2
(-2935 5160);
DISPLAY 0.680851 (-2935 5160);
PAINT MONO (-2935 5160);
FORCEPROP 0 LASTPIN (-2925 5100) $PN AK32
J 2
(-2935 5110);
DISPLAY 0.680851 (-2935 5110);
PAINT MONO (-2935 5110);
FORCEPROP 0 LASTPIN (-2925 5050) $PN AK4
J 2
(-2935 5060);
DISPLAY 0.680851 (-2935 5060);
PAINT MONO (-2935 5060);
FORCEPROP 0 LASTPIN (-2925 5000) $PN AL2
J 2
(-2935 5010);
DISPLAY 0.680851 (-2935 5010);
PAINT MONO (-2935 5010);
FORCEPROP 0 LASTPIN (-2925 4950) $PN AL34
J 2
(-2935 4960);
DISPLAY 0.680851 (-2935 4960);
PAINT MONO (-2935 4960);
FORCEPROP 0 LASTPIN (-2925 4900) $PN AM1
J 2
(-2935 4910);
DISPLAY 0.680851 (-2935 4910);
PAINT MONO (-2935 4910);
FORCEPROP 0 LASTPIN (-2925 4850) $PN AM35
J 2
(-2935 4860);
DISPLAY 0.680851 (-2935 4860);
PAINT MONO (-2935 4860);
FORCEPROP 0 LASTPIN (-2925 4800) $PN AU13
J 2
(-2935 4810);
DISPLAY 0.680851 (-2935 4810);
PAINT MONO (-2935 4810);
FORCEPROP 0 LASTPIN (-2925 4750) $PN AU22
J 2
(-2935 4760);
DISPLAY 0.680851 (-2935 4760);
PAINT MONO (-2935 4760);
FORCEPROP 0 LASTPIN (-2925 4700) $PN AU32
J 2
(-2935 4710);
DISPLAY 0.680851 (-2935 4710);
PAINT MONO (-2935 4710);
FORCEPROP 0 LASTPIN (-2925 4650) $PN AU4
J 2
(-2935 4660);
DISPLAY 0.680851 (-2935 4660);
PAINT MONO (-2935 4660);
FORCEPROP 0 LASTPIN (-2925 4600) $PN AV2
J 2
(-2935 4610);
DISPLAY 0.680851 (-2935 4610);
PAINT MONO (-2935 4610);
FORCEPROP 0 LASTPIN (-2925 4550) $PN AV34
J 2
(-2935 4560);
DISPLAY 0.680851 (-2935 4560);
PAINT MONO (-2935 4560);
FORCEPROP 0 LASTPIN (-2925 4500) $PN AW1
J 2
(-2935 4510);
DISPLAY 0.680851 (-2935 4510);
PAINT MONO (-2935 4510);
FORCEPROP 0 LASTPIN (-2925 4450) $PN AW35
J 2
(-2935 4460);
DISPLAY 0.680851 (-2935 4460);
PAINT MONO (-2935 4460);
FORCEPROP 0 LASTPIN (-2925 4400) $PN B19
J 2
(-2935 4410);
DISPLAY 0.680851 (-2935 4410);
PAINT MONO (-2935 4410);
FORCEPROP 0 LASTPIN (-2925 4350) $PN BD13
J 2
(-2935 4360);
DISPLAY 0.680851 (-2935 4360);
PAINT MONO (-2935 4360);
FORCEPROP 0 LASTPIN (-2925 4300) $PN BD22
J 2
(-2935 4310);
DISPLAY 0.680851 (-2935 4310);
PAINT MONO (-2935 4310);
FORCEPROP 0 LASTPIN (-2925 4250) $PN BD32
J 2
(-2935 4260);
DISPLAY 0.680851 (-2935 4260);
PAINT MONO (-2935 4260);
FORCEPROP 0 LASTPIN (-2925 4200) $PN BD4
J 2
(-2935 4210);
DISPLAY 0.680851 (-2935 4210);
PAINT MONO (-2935 4210);
FORCEPROP 0 LASTPIN (-2925 4150) $PN BE2
J 2
(-2935 4160);
DISPLAY 0.680851 (-2935 4160);
PAINT MONO (-2935 4160);
FORCEPROP 0 LASTPIN (-2925 4100) $PN BE34
J 2
(-2935 4110);
DISPLAY 0.680851 (-2935 4110);
PAINT MONO (-2935 4110);
FORCEPROP 0 LASTPIN (-2925 4050) $PN BF1
J 2
(-2935 4060);
DISPLAY 0.680851 (-2935 4060);
PAINT MONO (-2935 4060);
FORCEPROP 0 LASTPIN (-2925 4000) $PN BF35
J 2
(-2935 4010);
DISPLAY 0.680851 (-2935 4010);
PAINT MONO (-2935 4010);
FORCEPROP 0 LASTPIN (-2925 3950) $PN BL13
J 2
(-2935 3960);
DISPLAY 0.680851 (-2935 3960);
PAINT MONO (-2935 3960);
FORCEPROP 0 LASTPIN (-2925 3900) $PN BL22
J 2
(-2935 3910);
DISPLAY 0.680851 (-2935 3910);
PAINT MONO (-2935 3910);
FORCEPROP 0 LASTPIN (-2925 3850) $PN BL32
J 2
(-2935 3860);
DISPLAY 0.680851 (-2935 3860);
PAINT MONO (-2935 3860);
FORCEPROP 0 LASTPIN (-2925 3800) $PN BL4
J 2
(-2935 3810);
DISPLAY 0.680851 (-2935 3810);
PAINT MONO (-2935 3810);
FORCEPROP 0 LASTPIN (-2925 3750) $PN BM2
J 2
(-2935 3760);
DISPLAY 0.680851 (-2935 3760);
PAINT MONO (-2935 3760);
FORCEPROP 0 LASTPIN (-2925 3700) $PN BM34
J 2
(-2935 3710);
DISPLAY 0.680851 (-2935 3710);
PAINT MONO (-2935 3710);
FORCEPROP 0 LASTPIN (-2925 3650) $PN BN1
J 2
(-2935 3660);
DISPLAY 0.680851 (-2935 3660);
PAINT MONO (-2935 3660);
FORCEPROP 0 LASTPIN (-2925 3600) $PN BN35
J 2
(-2935 3610);
DISPLAY 0.680851 (-2935 3610);
PAINT MONO (-2935 3610);
FORCEPROP 0 LASTPIN (-2925 3550) $PN BV13
J 2
(-2935 3560);
DISPLAY 0.680851 (-2935 3560);
PAINT MONO (-2935 3560);
FORCEPROP 0 LASTPIN (-2925 3500) $PN BV22
J 2
(-2935 3510);
DISPLAY 0.680851 (-2935 3510);
PAINT MONO (-2935 3510);
FORCEPROP 0 LASTPIN (-2925 3450) $PN BV32
J 2
(-2935 3460);
DISPLAY 0.680851 (-2935 3460);
PAINT MONO (-2935 3460);
FORCEPROP 0 LASTPIN (-2925 3400) $PN BV4
J 2
(-2935 3410);
DISPLAY 0.680851 (-2935 3410);
PAINT MONO (-2935 3410);
FORCEPROP 0 LASTPIN (-2925 3350) $PN BW2
J 2
(-2935 3360);
DISPLAY 0.680851 (-2935 3360);
PAINT MONO (-2935 3360);
FORCEPROP 0 LASTPIN (-2925 3300) $PN BW34
J 2
(-2935 3310);
DISPLAY 0.680851 (-2935 3310);
PAINT MONO (-2935 3310);
FORCEPROP 0 LASTPIN (-2925 3250) $PN BY1
J 2
(-2935 3260);
DISPLAY 0.680851 (-2935 3260);
PAINT MONO (-2935 3260);
FORCEPROP 0 LASTPIN (-2925 3200) $PN BY35
J 2
(-2935 3210);
DISPLAY 0.680851 (-2935 3210);
PAINT MONO (-2935 3210);
FORCEPROP 0 LASTPIN (-2925 3150) $PN CE13
J 2
(-2935 3160);
DISPLAY 0.680851 (-2935 3160);
PAINT MONO (-2935 3160);
FORCEPROP 0 LASTPIN (-2925 3100) $PN CE22
J 2
(-2935 3110);
DISPLAY 0.680851 (-2935 3110);
PAINT MONO (-2935 3110);
FORCEPROP 0 LASTPIN (-2925 3050) $PN CE32
J 2
(-2935 3060);
DISPLAY 0.680851 (-2935 3060);
PAINT MONO (-2935 3060);
FORCEPROP 0 LASTPIN (-2925 3000) $PN CE4
J 2
(-2935 3010);
DISPLAY 0.680851 (-2935 3010);
PAINT MONO (-2935 3010);
FORCEPROP 0 LASTPIN (-2925 2950) $PN CF2
J 2
(-2935 2960);
DISPLAY 0.680851 (-2935 2960);
PAINT MONO (-2935 2960);
FORCEPROP 0 LASTPIN (-2925 2900) $PN CF34
J 2
(-2935 2910);
DISPLAY 0.680851 (-2935 2910);
PAINT MONO (-2935 2910);
FORCEPROP 0 LASTPIN (-2925 2850) $PN CG1
J 2
(-2935 2860);
DISPLAY 0.680851 (-2935 2860);
PAINT MONO (-2935 2860);
FORCEPROP 0 LASTPIN (-2925 2800) $PN CG35
J 2
(-2935 2810);
DISPLAY 0.680851 (-2935 2810);
PAINT MONO (-2935 2810);
FORCEPROP 0 LASTPIN (-2925 2750) $PN CM13
J 2
(-2935 2760);
DISPLAY 0.680851 (-2935 2760);
PAINT MONO (-2935 2760);
FORCEPROP 0 LASTPIN (-2925 2700) $PN CM22
J 2
(-2935 2710);
DISPLAY 0.680851 (-2935 2710);
PAINT MONO (-2935 2710);
FORCEPROP 0 LASTPIN (-2925 2650) $PN CM32
J 2
(-2935 2660);
DISPLAY 0.680851 (-2935 2660);
PAINT MONO (-2935 2660);
FORCEPROP 0 LASTPIN (-2925 2600) $PN CM4
J 2
(-2935 2610);
DISPLAY 0.680851 (-2935 2610);
PAINT MONO (-2935 2610);
FORCEPROP 0 LASTPIN (-2925 2550) $PN CN2
J 2
(-2935 2560);
DISPLAY 0.680851 (-2935 2560);
PAINT MONO (-2935 2560);
FORCEPROP 0 LASTPIN (-2925 2500) $PN CN34
J 2
(-2935 2510);
DISPLAY 0.680851 (-2935 2510);
PAINT MONO (-2935 2510);
FORCEPROP 0 LASTPIN (-2925 2450) $PN CP1
J 2
(-2935 2460);
DISPLAY 0.680851 (-2935 2460);
PAINT MONO (-2935 2460);
FORCEPROP 0 LASTPIN (-2925 2400) $PN CP35
J 2
(-2935 2410);
DISPLAY 0.680851 (-2935 2410);
PAINT MONO (-2935 2410);
FORCEPROP 0 LASTPIN (-2925 2350) $PN CW13
J 2
(-2935 2360);
DISPLAY 0.680851 (-2935 2360);
PAINT MONO (-2935 2360);
FORCEPROP 0 LASTPIN (-2925 2300) $PN CW22
J 2
(-2935 2310);
DISPLAY 0.680851 (-2935 2310);
PAINT MONO (-2935 2310);
FORCEPROP 0 LASTPIN (-2925 2250) $PN CW32
J 2
(-2935 2260);
DISPLAY 0.680851 (-2935 2260);
PAINT MONO (-2935 2260);
FORCEPROP 0 LASTPIN (-2925 2200) $PN CW4
J 2
(-2935 2210);
DISPLAY 0.680851 (-2935 2210);
PAINT MONO (-2935 2210);
FORCEPROP 0 LASTPIN (-2925 2150) $PN CY2
J 2
(-2935 2160);
DISPLAY 0.680851 (-2935 2160);
PAINT MONO (-2935 2160);
FORCEPROP 0 LASTPIN (-2925 2100) $PN CY34
J 2
(-2935 2110);
DISPLAY 0.680851 (-2935 2110);
PAINT MONO (-2935 2110);
FORCEPROP 0 LASTPIN (-2925 2050) $PN DA1
J 2
(-2935 2060);
DISPLAY 0.680851 (-2935 2060);
PAINT MONO (-2935 2060);
FORCEPROP 0 LASTPIN (-2925 2000) $PN DA35
J 2
(-2935 2010);
DISPLAY 0.680851 (-2935 2010);
PAINT MONO (-2935 2010);
FORCEPROP 0 LASTPIN (-2925 1950) $PN DF13
J 2
(-2935 1960);
DISPLAY 0.680851 (-2935 1960);
PAINT MONO (-2935 1960);
FORCEPROP 0 LASTPIN (-2925 1900) $PN DF22
J 2
(-2935 1910);
DISPLAY 0.680851 (-2935 1910);
PAINT MONO (-2935 1910);
FORCEPROP 0 LASTPIN (-2925 1850) $PN DF32
J 2
(-2935 1860);
DISPLAY 0.680851 (-2935 1860);
PAINT MONO (-2935 1860);
FORCEPROP 0 LASTPIN (-2925 1800) $PN DF4
J 2
(-2935 1810);
DISPLAY 0.680851 (-2935 1810);
PAINT MONO (-2935 1810);
FORCEPROP 0 LASTPIN (-2925 1750) $PN DG2
J 2
(-2935 1760);
DISPLAY 0.680851 (-2935 1760);
PAINT MONO (-2935 1760);
FORCEPROP 0 LASTPIN (-2925 1700) $PN DG34
J 2
(-2935 1710);
DISPLAY 0.680851 (-2935 1710);
PAINT MONO (-2935 1710);
FORCEPROP 0 LASTPIN (-2925 1650) $PN DH1
J 2
(-2935 1660);
DISPLAY 0.680851 (-2935 1660);
PAINT MONO (-2935 1660);
FORCEPROP 0 LASTPIN (-2925 1600) $PN DH35
J 2
(-2935 1610);
DISPLAY 0.680851 (-2935 1610);
PAINT MONO (-2935 1610);
FORCEPROP 0 LASTPIN (-2925 1550) $PN DN13
J 2
(-2935 1560);
DISPLAY 0.680851 (-2935 1560);
PAINT MONO (-2935 1560);
FORCEPROP 0 LASTPIN (-1975 5600) $PN DN22
J 0
(-1965 5610);
DISPLAY 0.680851 (-1965 5610);
PAINT MONO (-1965 5610);
FORCEPROP 0 LASTPIN (-1975 5550) $PN DN32
J 0
(-1965 5560);
DISPLAY 0.680851 (-1965 5560);
PAINT MONO (-1965 5560);
FORCEPROP 0 LASTPIN (-1975 5500) $PN DN4
J 0
(-1965 5510);
DISPLAY 0.680851 (-1965 5510);
PAINT MONO (-1965 5510);
FORCEPROP 0 LASTPIN (-1975 5450) $PN DP2
J 0
(-1965 5460);
DISPLAY 0.680851 (-1965 5460);
PAINT MONO (-1965 5460);
FORCEPROP 0 LASTPIN (-1975 5400) $PN DP34
J 0
(-1965 5410);
DISPLAY 0.680851 (-1965 5410);
PAINT MONO (-1965 5410);
FORCEPROP 0 LASTPIN (-1975 5350) $PN DR1
J 0
(-1965 5360);
DISPLAY 0.680851 (-1965 5360);
PAINT MONO (-1965 5360);
FORCEPROP 0 LASTPIN (-1975 5300) $PN DR35
J 0
(-1965 5310);
DISPLAY 0.680851 (-1965 5310);
PAINT MONO (-1965 5310);
FORCEPROP 0 LASTPIN (-1975 5250) $PN DY13
J 0
(-1965 5260);
DISPLAY 0.680851 (-1965 5260);
PAINT MONO (-1965 5260);
FORCEPROP 0 LASTPIN (-1975 5200) $PN DY22
J 0
(-1965 5210);
DISPLAY 0.680851 (-1965 5210);
PAINT MONO (-1965 5210);
FORCEPROP 0 LASTPIN (-1975 5150) $PN DY32
J 0
(-1965 5160);
DISPLAY 0.680851 (-1965 5160);
PAINT MONO (-1965 5160);
FORCEPROP 0 LASTPIN (-1975 5100) $PN DY4
J 0
(-1965 5110);
DISPLAY 0.680851 (-1965 5110);
PAINT MONO (-1965 5110);
FORCEPROP 0 LASTPIN (-1975 5050) $PN E14
J 0
(-1965 5060);
DISPLAY 0.680851 (-1965 5060);
PAINT MONO (-1965 5060);
FORCEPROP 0 LASTPIN (-1975 5000) $PN E27
J 0
(-1965 5010);
DISPLAY 0.680851 (-1965 5010);
PAINT MONO (-1965 5010);
FORCEPROP 0 LASTPIN (-1975 4950) $PN E33
J 0
(-1965 4960);
DISPLAY 0.680851 (-1965 4960);
PAINT MONO (-1965 4960);
FORCEPROP 0 LASTPIN (-1975 4900) $PN EA2
J 0
(-1965 4910);
DISPLAY 0.680851 (-1965 4910);
PAINT MONO (-1965 4910);
FORCEPROP 0 LASTPIN (-1975 4850) $PN EA34
J 0
(-1965 4860);
DISPLAY 0.680851 (-1965 4860);
PAINT MONO (-1965 4860);
FORCEPROP 0 LASTPIN (-1975 4800) $PN EB1
J 0
(-1965 4810);
DISPLAY 0.680851 (-1965 4810);
PAINT MONO (-1965 4810);
FORCEPROP 0 LASTPIN (-1975 4750) $PN EB35
J 0
(-1965 4760);
DISPLAY 0.680851 (-1965 4760);
PAINT MONO (-1965 4760);
FORCEPROP 0 LASTPIN (-1975 4700) $PN EG13
J 0
(-1965 4710);
DISPLAY 0.680851 (-1965 4710);
PAINT MONO (-1965 4710);
FORCEPROP 0 LASTPIN (-1975 4650) $PN EG22
J 0
(-1965 4660);
DISPLAY 0.680851 (-1965 4660);
PAINT MONO (-1965 4660);
FORCEPROP 0 LASTPIN (-1975 4600) $PN EG32
J 0
(-1965 4610);
DISPLAY 0.680851 (-1965 4610);
PAINT MONO (-1965 4610);
FORCEPROP 0 LASTPIN (-1975 4550) $PN EG4
J 0
(-1965 4560);
DISPLAY 0.680851 (-1965 4560);
PAINT MONO (-1965 4560);
FORCEPROP 0 LASTPIN (-1975 4500) $PN EH2
J 0
(-1965 4510);
DISPLAY 0.680851 (-1965 4510);
PAINT MONO (-1965 4510);
FORCEPROP 0 LASTPIN (-1975 4450) $PN EH34
J 0
(-1965 4460);
DISPLAY 0.680851 (-1965 4460);
PAINT MONO (-1965 4460);
FORCEPROP 0 LASTPIN (-1975 4400) $PN EJ1
J 0
(-1965 4410);
DISPLAY 0.680851 (-1965 4410);
PAINT MONO (-1965 4410);
FORCEPROP 0 LASTPIN (-1975 4350) $PN EJ35
J 0
(-1965 4360);
DISPLAY 0.680851 (-1965 4360);
PAINT MONO (-1965 4360);
FORCEPROP 0 LASTPIN (-1975 4300) $PN EP13
J 0
(-1965 4310);
DISPLAY 0.680851 (-1965 4310);
PAINT MONO (-1965 4310);
FORCEPROP 0 LASTPIN (-1975 4250) $PN EP22
J 0
(-1965 4260);
DISPLAY 0.680851 (-1965 4260);
PAINT MONO (-1965 4260);
FORCEPROP 0 LASTPIN (-1975 4200) $PN EP32
J 0
(-1965 4210);
DISPLAY 0.680851 (-1965 4210);
PAINT MONO (-1965 4210);
FORCEPROP 0 LASTPIN (-1975 4150) $PN EP4
J 0
(-1965 4160);
DISPLAY 0.680851 (-1965 4160);
PAINT MONO (-1965 4160);
FORCEPROP 0 LASTPIN (-1975 4100) $PN ER2
J 0
(-1965 4110);
DISPLAY 0.680851 (-1965 4110);
PAINT MONO (-1965 4110);
FORCEPROP 0 LASTPIN (-1975 4050) $PN ER34
J 0
(-1965 4060);
DISPLAY 0.680851 (-1965 4060);
PAINT MONO (-1965 4060);
FORCEPROP 0 LASTPIN (-1975 4000) $PN ET1
J 0
(-1965 4010);
DISPLAY 0.680851 (-1965 4010);
PAINT MONO (-1965 4010);
FORCEPROP 0 LASTPIN (-1975 3950) $PN ET35
J 0
(-1965 3960);
DISPLAY 0.680851 (-1965 3960);
PAINT MONO (-1965 3960);
FORCEPROP 0 LASTPIN (-1975 3900) $PN FA15
J 0
(-1965 3910);
DISPLAY 0.680851 (-1965 3910);
PAINT MONO (-1965 3910);
FORCEPROP 0 LASTPIN (-1975 3850) $PN FA32
J 0
(-1965 3860);
DISPLAY 0.680851 (-1965 3860);
PAINT MONO (-1965 3860);
FORCEPROP 0 LASTPIN (-1975 3800) $PN FB2
J 0
(-1965 3810);
DISPLAY 0.680851 (-1965 3810);
PAINT MONO (-1965 3810);
FORCEPROP 0 LASTPIN (-1975 3750) $PN FB34
J 0
(-1965 3760);
DISPLAY 0.680851 (-1965 3760);
PAINT MONO (-1965 3760);
FORCEPROP 0 LASTPIN (-1975 3700) $PN FC19
J 0
(-1965 3710);
DISPLAY 0.680851 (-1965 3710);
PAINT MONO (-1965 3710);
FORCEPROP 0 LASTPIN (-1975 3650) $PN FC23
J 0
(-1965 3660);
DISPLAY 0.680851 (-1965 3660);
PAINT MONO (-1965 3660);
FORCEPROP 0 LASTPIN (-1975 3600) $PN FC25
J 0
(-1965 3610);
DISPLAY 0.680851 (-1965 3610);
PAINT MONO (-1965 3610);
FORCEPROP 0 LASTPIN (-1975 3550) $PN FC28
J 0
(-1965 3560);
DISPLAY 0.680851 (-1965 3560);
PAINT MONO (-1965 3560);
FORCEPROP 0 LASTPIN (-1975 3500) $PN FC3
J 0
(-1965 3510);
DISPLAY 0.680851 (-1965 3510);
PAINT MONO (-1965 3510);
FORCEPROP 0 LASTPIN (-1975 3450) $PN FC6
J 0
(-1965 3460);
DISPLAY 0.680851 (-1965 3460);
PAINT MONO (-1965 3460);
FORCEPROP 0 LASTPIN (-1975 3400) $PN FC9
J 0
(-1965 3410);
DISPLAY 0.680851 (-1965 3410);
PAINT MONO (-1965 3410);
FORCEPROP 0 LASTPIN (-1975 3350) $PN FD1
J 0
(-1965 3360);
DISPLAY 0.680851 (-1965 3360);
PAINT MONO (-1965 3360);
FORCEPROP 0 LASTPIN (-1975 3300) $PN FD35
J 0
(-1965 3310);
DISPLAY 0.680851 (-1965 3310);
PAINT MONO (-1965 3310);
FORCEPROP 0 LASTPIN (-1975 3250) $PN FF14
J 0
(-1965 3260);
DISPLAY 0.680851 (-1965 3260);
PAINT MONO (-1965 3260);
FORCEPROP 0 LASTPIN (-1975 3200) $PN FF21
J 0
(-1965 3210);
DISPLAY 0.680851 (-1965 3210);
PAINT MONO (-1965 3210);
FORCEPROP 0 LASTPIN (-1975 3150) $PN FJ12
J 0
(-1965 3160);
DISPLAY 0.680851 (-1965 3160);
PAINT MONO (-1965 3160);
FORCEPROP 0 LASTPIN (-1975 3100) $PN FJ19
J 0
(-1965 3110);
DISPLAY 0.680851 (-1965 3110);
PAINT MONO (-1965 3110);
FORCEPROP 0 LASTPIN (-1975 3050) $PN H12
J 0
(-1965 3060);
DISPLAY 0.680851 (-1965 3060);
PAINT MONO (-1965 3060);
FORCEPROP 0 LASTPIN (-1975 3000) $PN H16
J 0
(-1965 3010);
DISPLAY 0.680851 (-1965 3010);
PAINT MONO (-1965 3010);
FORCEPROP 0 LASTPIN (-1975 2950) $PN H19
J 0
(-1965 2960);
DISPLAY 0.680851 (-1965 2960);
PAINT MONO (-1965 2960);
FORCEPROP 0 LASTPIN (-1975 2900) $PN H31
J 0
(-1965 2910);
DISPLAY 0.680851 (-1965 2910);
PAINT MONO (-1965 2910);
FORCEPROP 0 LASTPIN (-1975 2850) $PN J22
J 0
(-1965 2860);
DISPLAY 0.680851 (-1965 2860);
PAINT MONO (-1965 2860);
FORCEPROP 0 LASTPIN (-1975 2800) $PN J4
J 0
(-1965 2810);
DISPLAY 0.680851 (-1965 2810);
PAINT MONO (-1965 2810);
FORCEPROP 0 LASTPIN (-1975 2750) $PN K2
J 0
(-1965 2760);
DISPLAY 0.680851 (-1965 2760);
PAINT MONO (-1965 2760);
FORCEPROP 0 LASTPIN (-1975 2700) $PN K34
J 0
(-1965 2710);
DISPLAY 0.680851 (-1965 2710);
PAINT MONO (-1965 2710);
FORCEPROP 0 LASTPIN (-1975 2650) $PN L1
J 0
(-1965 2660);
DISPLAY 0.680851 (-1965 2660);
PAINT MONO (-1965 2660);
FORCEPROP 0 LASTPIN (-1975 2600) $PN L35
J 0
(-1965 2610);
DISPLAY 0.680851 (-1965 2610);
PAINT MONO (-1965 2610);
FORCEPROP 0 LASTPIN (-1975 2550) $PN T13
J 0
(-1965 2560);
DISPLAY 0.680851 (-1965 2560);
PAINT MONO (-1965 2560);
FORCEPROP 0 LASTPIN (-1975 2500) $PN T22
J 0
(-1965 2510);
DISPLAY 0.680851 (-1965 2510);
PAINT MONO (-1965 2510);
FORCEPROP 0 LASTPIN (-1975 2450) $PN T32
J 0
(-1965 2460);
DISPLAY 0.680851 (-1965 2460);
PAINT MONO (-1965 2460);
FORCEPROP 0 LASTPIN (-1975 2400) $PN T4
J 0
(-1965 2410);
DISPLAY 0.680851 (-1965 2410);
PAINT MONO (-1965 2410);
FORCEPROP 0 LASTPIN (-1975 2350) $PN U2
J 0
(-1965 2360);
DISPLAY 0.680851 (-1965 2360);
PAINT MONO (-1965 2360);
FORCEPROP 0 LASTPIN (-1975 2300) $PN U34
J 0
(-1965 2310);
DISPLAY 0.680851 (-1965 2310);
PAINT MONO (-1965 2310);
FORCEPROP 0 LASTPIN (-1975 2250) $PN V1
J 0
(-1965 2260);
DISPLAY 0.680851 (-1965 2260);
PAINT MONO (-1965 2260);
FORCEPROP 0 LASTPIN (-1975 2200) $PN V35
J 0
(-1965 2210);
DISPLAY 0.680851 (-1965 2210);
PAINT MONO (-1965 2210);
FORCEPROP 0 LASTPIN (-1975 2100) $PN A1
J 0
(-1965 2110);
DISPLAY 0.680851 (-1965 2110);
PAINT MONO (-1965 2110);
FORCEPROP 0 LASTPIN (-1975 2050) $PN A35
J 0
(-1965 2060);
DISPLAY 0.680851 (-1965 2060);
PAINT MONO (-1965 2060);
FORCEPROP 0 LASTPIN (-1975 2000) $PN C2
J 0
(-1965 2010);
DISPLAY 0.680851 (-1965 2010);
PAINT MONO (-1965 2010);
FORCEPROP 0 LASTPIN (-1975 1950) $PN C34
J 0
(-1965 1960);
DISPLAY 0.680851 (-1965 1960);
PAINT MONO (-1965 1960);
FORCEPROP 0 LASTPIN (-1975 1900) $PN D1
J 0
(-1965 1910);
DISPLAY 0.680851 (-1965 1910);
PAINT MONO (-1965 1910);
FORCEPROP 0 LASTPIN (-1975 1850) $PN D35
J 0
(-1965 1860);
DISPLAY 0.680851 (-1965 1860);
PAINT MONO (-1965 1860);
FORCEPROP 0 LASTPIN (-1975 1800) $PN FE2
J 0
(-1965 1810);
DISPLAY 0.680851 (-1965 1810);
PAINT MONO (-1965 1810);
FORCEPROP 0 LASTPIN (-1975 1750) $PN FE34
J 0
(-1965 1760);
DISPLAY 0.680851 (-1965 1760);
PAINT MONO (-1965 1760);
FORCEPROP 0 LASTPIN (-1975 1700) $PN FG1
J 0
(-1965 1710);
DISPLAY 0.680851 (-1965 1710);
PAINT MONO (-1965 1710);
FORCEPROP 0 LASTPIN (-1975 1650) $PN FG35
J 0
(-1965 1660);
DISPLAY 0.680851 (-1965 1660);
PAINT MONO (-1965 1660);
FORCEPROP 0 LASTPIN (-1975 1600) $PN FH2
J 0
(-1965 1610);
DISPLAY 0.680851 (-1965 1610);
PAINT MONO (-1965 1610);
FORCEPROP 0 LASTPIN (-1975 1550) $PN FH34
J 0
(-1965 1560);
DISPLAY 0.680851 (-1965 1560);
PAINT MONO (-1965 1560);
FORCEPROP 2 LAST PART_TYPE SMLF
J 0
(-2775 6025);
DISPLAY 0.680851 (-2775 6025);
FORCEPROP 2 LAST VALUE PT5161LRS
J 0
(-2775 5975);
DISPLAY 0.680851 (-2775 5975);
FORCEPROP 1 LAST MATERIAL IC
J 0
(-2775 5775);
DISPLAY 0.723404 (-2775 5775);
PAINT GREEN (-2775 5775);
FORCEPROP 1 LAST NEEDS_NO_SIZE TRUE
J 0
(-2425 3600);
DISPLAY 0.723404 (-2425 3600);
PAINT GREEN (-2425 3600);
DISPLAY INVISIBLE (-2425 3600);
FORCEPROP 1 LAST CDS_LMAN_SYM_OUTLINE -350,2150,300,-2150
J 0
(-2425 3600);
DISPLAY 0.468085 (-2425 3600);
PAINT GREEN (-2425 3600);
DISPLAY INVISIBLE (-2425 3600);
FORCEPROP 2 LAST CDS_LIB pure_quanta
J 0
(-2425 3600);
DISPLAY INVISIBLE (-2425 3600);
FORCEPROP 1 LAST PATH I17
J 0
(-2425 3600);
DISPLAY 0.723404 (-2425 3600);
PAINT GREEN (-2425 3600);
DISPLAY INVISIBLE (-2425 3600);
FORCEPROP 1 LAST PART_NUMBER AJ051610U03
J 0
(-2775 5850);
DISPLAY 0.723404 (-2775 5850);
PAINT GREEN (-2775 5850);
DISPLAY INVISIBLE (-2775 5850);
FORCEADD Q_RES..2
(-7650 3375);
FORCEPROP 1 LAST LOCATION R6901
J 0
(-7605 3500);
DISPLAY 0.978723 (-7605 3500);
PAINT WHITE (-7605 3500);
FORCEPROP 0 LAST $SEC 1
J 0
(-7600 3550);
DISPLAY 0.680851 (-7600 3550);
PAINT MONO (-7600 3550);
DISPLAY INVISIBLE (-7600 3550);
FORCEPROP 0 LAST CDS_SEC 1
J 0
(-7600 3550);
DISPLAY 0.680851 (-7600 3550);
DISPLAY INVISIBLE (-7600 3550);
FORCEPROP 1 LASTPIN (-7650 3475) $PN 1
J 0
(-7645 3437);
DISPLAY 0.787234 (-7645 3437);
PAINT MONO (-7645 3437);
FORCEPROP 1 LASTPIN (-7650 3275) $PN 2
J 0
(-7645 3285);
DISPLAY 0.787234 (-7645 3285);
PAINT MONO (-7645 3285);
FORCEPROP 1 LAST TOLERANCE 1%
J 0
(-7605 3400);
DISPLAY 0.978723 (-7605 3400);
FORCEPROP 1 LAST VALUE 200
J 0
(-7605 3450);
DISPLAY 0.978723 (-7605 3450);
FORCEPROP 1 LAST WATTAGE 1/20W
J 0
(-7610 3350);
DISPLAY 0.978723 (-7610 3350);
FORCEPROP 1 LAST MATERIAL CHIP
J 0
(-7610 3300);
DISPLAY 0.978723 (-7610 3300);
FORCEPROP 1 LAST PACK_TYPE 0201LF
J 0
(-7610 3200);
DISPLAY 0.978723 (-7610 3200);
FORCEPROP 2 LAST CDS_LIB pure_quanta
J 0
(-7650 3375);
DISPLAY INVISIBLE (-7650 3375);
FORCEPROP 1 LAST PATH I18
J 0
(-7600 3550);
DISPLAY 0.978723 (-7600 3550);
PAINT WHITE (-7600 3550);
DISPLAY INVISIBLE (-7600 3550);
FORCEPROP 1 LAST PART_NUMBER CS12001FE12
J 0
(-7610 3250);
DISPLAY 0.978723 (-7610 3250);
DISPLAY INVISIBLE (-7610 3250);
FORCEADD Q_RES..2
(-8675 3925);
FORCEPROP 1 LAST LOCATION R6900
J 0
(-8630 4050);
DISPLAY 0.787234 (-8630 4050);
PAINT SKYBLUE (-8630 4050);
FORCEPROP 0 LAST $SEC 1
J 0
(-8625 4100);
DISPLAY 0.680851 (-8625 4100);
PAINT MONO (-8625 4100);
DISPLAY INVISIBLE (-8625 4100);
FORCEPROP 0 LAST CDS_SEC 1
J 0
(-8625 4100);
DISPLAY 0.680851 (-8625 4100);
DISPLAY INVISIBLE (-8625 4100);
FORCEPROP 1 LASTPIN (-8675 4025) $PN 1
J 0
(-8670 3987);
DISPLAY 0.787234 (-8670 3987);
PAINT MONO (-8670 3987);
FORCEPROP 1 LASTPIN (-8675 3825) $PN 2
J 0
(-8670 3835);
DISPLAY 0.787234 (-8670 3835);
PAINT MONO (-8670 3835);
FORCEPROP 1 LAST MATERIAL EMPTY
J 0
(-8635 3850);
DISPLAY 0.787234 (-8635 3850);
PAINT RED (-8635 3850);
FORCEPROP 1 LAST VALUE 1K
J 0
(-8630 4000);
DISPLAY 0.787234 (-8630 4000);
FORCEPROP 1 LAST TOLERANCE 1%
J 0
(-8630 3950);
DISPLAY 0.787234 (-8630 3950);
FORCEPROP 1 LAST PACK_TYPE 0201LF
J 0
(-8635 3750);
DISPLAY 0.787234 (-8635 3750);
FORCEPROP 1 LAST WATTAGE 1/20W
J 0
(-8635 3900);
DISPLAY 0.787234 (-8635 3900);
FORCEPROP 2 LAST CDS_LIB pure_quanta
J 0
(-8675 3925);
DISPLAY INVISIBLE (-8675 3925);
FORCEPROP 1 LAST PATH I19
J 0
(-8625 4100);
DISPLAY 0.978723 (-8625 4100);
PAINT WHITE (-8625 4100);
DISPLAY INVISIBLE (-8625 4100);
FORCEPROP 1 LAST PART_NUMBER CS21001FE07
J 0
(-8635 3800);
DISPLAY 0.978723 (-8635 3800);
DISPLAY INVISIBLE (-8635 3800);
FORCEADD P1V0..1
(-8675 4150);
FORCEPROP 3 LASTPIN (-8675 4100) SIG_NAME P1V8_CPU1_RT_1D\g
J 0
(-8665 4110);
DISPLAY 0.659574 (-8665 4110);
PAINT MONO (-8665 4110);
DISPLAY INVISIBLE (-8665 4110);
FORCEPROP 1 LAST HDL_POWER P1V8_CPU1_RT_1D
J 1
(-8675 4200);
DISPLAY 0.489362 (-8675 4200);
PAINT SKYBLUE (-8675 4200);
FORCEPROP 2 LAST CDS_LIB pure_quanta_power
J 0
(-8675 4150);
DISPLAY INVISIBLE (-8675 4150);
FORCEPROP 1 LAST PATH I2
J 0
(-8625 4175);
DISPLAY 0.872340 (-8625 4175);
PAINT AQUA (-8625 4175);
DISPLAY INVISIBLE (-8625 4175);
FORCEADD UNIVERSAL_GND..1
(-7650 3125);
FORCEPROP 3 LASTPIN (-7650 3175) SIG_NAME GND\g
J 0
(-7640 3185);
DISPLAY 0.659574 (-7640 3185);
PAINT MONO (-7640 3185);
DISPLAY INVISIBLE (-7640 3185);
FORCEPROP 2 LAST CDS_LIB pure_quanta_power
J 0
(-7650 3125);
DISPLAY INVISIBLE (-7650 3125);
FORCEPROP 1 LAST HDL_POWER GND
J 1
(-7625 3050);
DISPLAY 0.872340 (-7625 3050);
PAINT GREEN (-7625 3050);
DISPLAY INVISIBLE (-7625 3050);
FORCEPROP 1 LAST PATH I3
J 0
(-7575 3125);
DISPLAY 0.872340 (-7575 3125);
PAINT AQUA (-7575 3125);
DISPLAY INVISIBLE (-7575 3125);
FORCEADD PT5161LRS..4
(-6500 4175);
FORCEPROP 1 LAST LOCATION U6017
J 0
(-6950 5100);
DISPLAY 0.723404 (-6950 5100);
PAINT GREEN (-6950 5100);
FORCEPROP 0 LAST $SEC 4
J 0
(-6950 5250);
DISPLAY 0.680851 (-6950 5250);
PAINT MONO (-6950 5250);
DISPLAY INVISIBLE (-6950 5250);
FORCEPROP 0 LAST CDS_SEC 4
J 0
(-6950 5250);
DISPLAY 0.680851 (-6950 5250);
DISPLAY INVISIBLE (-6950 5250);
FORCEPROP 0 LASTPIN (-7100 4775) $PN BV20
J 2
(-7110 4785);
DISPLAY 0.680851 (-7110 4785);
PAINT MONO (-7110 4785);
FORCEPROP 0 LASTPIN (-7100 4725) $PN CE17
J 2
(-7110 4735);
DISPLAY 0.680851 (-7110 4735);
PAINT MONO (-7110 4735);
FORCEPROP 0 LASTPIN (-7100 4675) $PN CE20
J 2
(-7110 4685);
DISPLAY 0.680851 (-7110 4685);
PAINT MONO (-7110 4685);
FORCEPROP 0 LASTPIN (-7100 4625) $PN CM17
J 2
(-7110 4635);
DISPLAY 0.680851 (-7110 4635);
PAINT MONO (-7110 4635);
FORCEPROP 0 LASTPIN (-7100 4575) $PN CM20
J 2
(-7110 4585);
DISPLAY 0.680851 (-7110 4585);
PAINT MONO (-7110 4585);
FORCEPROP 0 LASTPIN (-7100 4125) $PN BV17
J 2
(-7110 4135);
DISPLAY 0.680851 (-7110 4135);
PAINT MONO (-7110 4135);
FORCEPROP 0 LASTPIN (-5950 4775) $PN AC17
J 0
(-5940 4785);
DISPLAY 0.680851 (-5940 4785);
PAINT MONO (-5940 4785);
FORCEPROP 0 LASTPIN (-5950 4725) $PN AC20
J 0
(-5940 4735);
DISPLAY 0.680851 (-5940 4735);
PAINT MONO (-5940 4735);
FORCEPROP 0 LASTPIN (-5950 4675) $PN AK17
J 0
(-5940 4685);
DISPLAY 0.680851 (-5940 4685);
PAINT MONO (-5940 4685);
FORCEPROP 0 LASTPIN (-5950 4625) $PN AK20
J 0
(-5940 4635);
DISPLAY 0.680851 (-5940 4635);
PAINT MONO (-5940 4635);
FORCEPROP 0 LASTPIN (-5950 4575) $PN AU17
J 0
(-5940 4585);
DISPLAY 0.680851 (-5940 4585);
PAINT MONO (-5940 4585);
FORCEPROP 0 LASTPIN (-5950 4525) $PN AU20
J 0
(-5940 4535);
DISPLAY 0.680851 (-5940 4535);
PAINT MONO (-5940 4535);
FORCEPROP 0 LASTPIN (-5950 4475) $PN BD17
J 0
(-5940 4485);
DISPLAY 0.680851 (-5940 4485);
PAINT MONO (-5940 4485);
FORCEPROP 0 LASTPIN (-5950 4425) $PN BD20
J 0
(-5940 4435);
DISPLAY 0.680851 (-5940 4435);
PAINT MONO (-5940 4435);
FORCEPROP 0 LASTPIN (-5950 4375) $PN DF17
J 0
(-5940 4385);
DISPLAY 0.680851 (-5940 4385);
PAINT MONO (-5940 4385);
FORCEPROP 0 LASTPIN (-5950 4325) $PN DF20
J 0
(-5940 4335);
DISPLAY 0.680851 (-5940 4335);
PAINT MONO (-5940 4335);
FORCEPROP 0 LASTPIN (-5950 4275) $PN DN17
J 0
(-5940 4285);
DISPLAY 0.680851 (-5940 4285);
PAINT MONO (-5940 4285);
FORCEPROP 0 LASTPIN (-5950 4225) $PN DN20
J 0
(-5940 4235);
DISPLAY 0.680851 (-5940 4235);
PAINT MONO (-5940 4235);
FORCEPROP 0 LASTPIN (-5950 4175) $PN DY17
J 0
(-5940 4185);
DISPLAY 0.680851 (-5940 4185);
PAINT MONO (-5940 4185);
FORCEPROP 0 LASTPIN (-5950 4125) $PN DY20
J 0
(-5940 4135);
DISPLAY 0.680851 (-5940 4135);
PAINT MONO (-5940 4135);
FORCEPROP 0 LASTPIN (-5950 4075) $PN EG17
J 0
(-5940 4085);
DISPLAY 0.680851 (-5940 4085);
PAINT MONO (-5940 4085);
FORCEPROP 0 LASTPIN (-5950 4025) $PN EG20
J 0
(-5940 4035);
DISPLAY 0.680851 (-5940 4035);
PAINT MONO (-5940 4035);
FORCEPROP 0 LASTPIN (-5950 3975) $PN EP17
J 0
(-5940 3985);
DISPLAY 0.680851 (-5940 3985);
PAINT MONO (-5940 3985);
FORCEPROP 0 LASTPIN (-5950 3925) $PN EP20
J 0
(-5940 3935);
DISPLAY 0.680851 (-5940 3935);
PAINT MONO (-5940 3935);
FORCEPROP 0 LASTPIN (-5950 3875) $PN T17
J 0
(-5940 3885);
DISPLAY 0.680851 (-5940 3885);
PAINT MONO (-5940 3885);
FORCEPROP 0 LASTPIN (-5950 3825) $PN T20
J 0
(-5940 3835);
DISPLAY 0.680851 (-5940 3835);
PAINT MONO (-5940 3835);
FORCEPROP 0 LASTPIN (-5950 3675) $PN BL17
J 0
(-5940 3685);
DISPLAY 0.680851 (-5940 3685);
PAINT MONO (-5940 3685);
FORCEPROP 0 LASTPIN (-5950 3625) $PN BL20
J 0
(-5940 3635);
DISPLAY 0.680851 (-5940 3635);
PAINT MONO (-5940 3635);
FORCEPROP 0 LASTPIN (-5950 3575) $PN CW17
J 0
(-5940 3585);
DISPLAY 0.680851 (-5940 3585);
PAINT MONO (-5940 3585);
FORCEPROP 0 LASTPIN (-5950 3525) $PN CW20
J 0
(-5940 3535);
DISPLAY 0.680851 (-5940 3535);
PAINT MONO (-5940 3535);
FORCEPROP 0 LASTPIN (-7100 3675) $PN G1
J 2
(-7110 3685);
DISPLAY 0.680851 (-7110 3685);
PAINT MONO (-7110 3685);
FORCEPROP 2 LAST PART_TYPE SMLF
J 0
(-6950 5200);
DISPLAY 0.680851 (-6950 5200);
FORCEPROP 2 LAST VALUE PT5161LRS
J 0
(-6950 5150);
DISPLAY 0.680851 (-6950 5150);
FORCEPROP 1 LAST MATERIAL IC
J 0
(-6950 4950);
DISPLAY 0.723404 (-6950 4950);
PAINT GREEN (-6950 4950);
FORCEPROP 1 LAST NEEDS_NO_SIZE TRUE
J 0
(-6500 4175);
DISPLAY 0.723404 (-6500 4175);
PAINT GREEN (-6500 4175);
DISPLAY INVISIBLE (-6500 4175);
FORCEPROP 1 LAST CDS_LMAN_SYM_OUTLINE -450,750,400,-750
J 0
(-6500 4175);
DISPLAY 0.468085 (-6500 4175);
PAINT GREEN (-6500 4175);
DISPLAY INVISIBLE (-6500 4175);
FORCEPROP 2 LAST CDS_LIB pure_quanta
J 0
(-6500 4175);
DISPLAY INVISIBLE (-6500 4175);
FORCEPROP 1 LAST PATH I5
J 0
(-6500 4175);
DISPLAY 0.723404 (-6500 4175);
PAINT GREEN (-6500 4175);
DISPLAY INVISIBLE (-6500 4175);
FORCEPROP 1 LAST PART_NUMBER AJ051610U03
J 0
(-6950 5025);
DISPLAY 0.723404 (-6950 5025);
PAINT GREEN (-6950 5025);
DISPLAY INVISIBLE (-6950 5025);
FORCEADD P1V0..1
(-4650 3825);
FORCEPROP 3 LASTPIN (-4650 3775) SIG_NAME P0V9_CPU1_RT_2D\g
J 0
(-4640 3785);
DISPLAY 0.659574 (-4640 3785);
PAINT MONO (-4640 3785);
DISPLAY INVISIBLE (-4640 3785);
FORCEPROP 1 LAST HDL_POWER P0V9_CPU1_RT_2D
J 1
(-4650 3875);
DISPLAY 0.489362 (-4650 3875);
PAINT SKYBLUE (-4650 3875);
FORCEPROP 2 LAST CDS_LIB pure_quanta_power
J 0
(-4650 3825);
DISPLAY INVISIBLE (-4650 3825);
FORCEPROP 1 LAST PATH I6
J 0
(-4600 3850);
DISPLAY 0.872340 (-4600 3850);
PAINT AQUA (-4600 3850);
DISPLAY INVISIBLE (-4600 3850);
FORCEADD P1V0..1
(-8350 4425);
FORCEPROP 3 LASTPIN (-8350 4375) SIG_NAME P1V8_CPU1_RT3_1A_1D\g
J 0
(-8340 4385);
DISPLAY 0.659574 (-8340 4385);
PAINT MONO (-8340 4385);
DISPLAY INVISIBLE (-8340 4385);
FORCEPROP 1 LAST HDL_POWER P1V8_CPU1_RT3_1A_1D
J 1
(-8350 4475);
DISPLAY 0.489362 (-8350 4475);
FORCEPROP 2 LAST CDS_LIB pure_quanta_power
J 0
(-8350 4425);
DISPLAY INVISIBLE (-8350 4425);
FORCEPROP 1 LAST PATH I7
J 0
(-8300 4450);
DISPLAY 0.872340 (-8300 4450);
PAINT AQUA (-8300 4450);
DISPLAY INVISIBLE (-8300 4450);
FORCEADD P1V0..1
(-7775 4875);
FORCEPROP 3 LASTPIN (-7775 4825) SIG_NAME P1V8_CPU1_RT3_1A\g
J 0
(-7765 4835);
DISPLAY 0.659574 (-7765 4835);
PAINT MONO (-7765 4835);
DISPLAY INVISIBLE (-7765 4835);
FORCEPROP 1 LAST HDL_POWER P1V8_CPU1_RT3_1A
J 1
(-7775 4925);
DISPLAY 0.489362 (-7775 4925);
FORCEPROP 2 LAST CDS_LIB pure_quanta_power
J 0
(-7775 4875);
DISPLAY INVISIBLE (-7775 4875);
FORCEPROP 1 LAST PATH I8
J 0
(-7725 4900);
DISPLAY 0.872340 (-7725 4900);
PAINT AQUA (-7725 4900);
DISPLAY INVISIBLE (-7725 4900);
FORCEADD VCC_CORE..1
(-5250 4575);
FORCEPROP 3 LASTPIN (-5250 4525) SIG_NAME P0V9_CPU1_RT3_2A_2D\g
J 0
(-5240 4535);
DISPLAY 0.659574 (-5240 4535);
PAINT MONO (-5240 4535);
DISPLAY INVISIBLE (-5240 4535);
FORCEPROP 1 LAST HDL_POWER P0V9_CPU1_RT3_2A_2D
J 1
(-5250 4625);
DISPLAY 0.617021 (-5250 4625);
FORCEPROP 2 LAST CDS_LIB pure_quanta_power
J 0
(-5250 4575);
DISPLAY INVISIBLE (-5250 4575);
FORCEPROP 1 LAST PATH I9
J 0
(-5200 4600);
DISPLAY 0.872340 (-5200 4600);
PAINT AQUA (-5200 4600);
DISPLAY INVISIBLE (-5200 4600);
FORCEADD QUANTA_TITLE_BLOCK_C..1
(0 0);
FORCEPROP 0 LAST CDS_CON_LAST_MODIFIED Thu Sep 14 16:13:06 2023
J 0
(-1885 15);
DISPLAY INVISIBLE (-1885 15);
FORCEPROP 1 LAST CUSTOM_TXT_CDS <CON_LAST_MODIFIED>
J 0
(-1885 15);
DISPLAY 0.978723 (-1885 15);
FORCEPROP 2 LAST CUSTOM_TXT_CDS <XR_PAGE_TITLE>
J 0
(-7890 5250);
DISPLAY 0.638298 (-7890 5250);
PAINT PINK (-7890 5250);
DISPLAY INVISIBLE (-7890 5250);
FORCEPROP 1 LAST CUSTOM_TXT_CDS <NAME_2>
J 0
(-3175 50);
FORCEPROP 1 LAST CUSTOM_TXT_CDS <NAME_1>
J 0
(-3175 175);
FORCEPROP 1 LAST CUSTOM_TXT_CDS <Q_NUMBER>
J 0
(-1403 103);
DISPLAY 1.212766 (-1403 103);
FORCEPROP 1 LAST CUSTOM_TXT_CDS <Q_PROJ>
J 0
(-2382 102);
DISPLAY 1.212766 (-2382 102);
FORCEPROP 1 LAST CUSTOM_TXT_CDS <Q_REV>
J 0
(-184 103);
DISPLAY 1.212766 (-184 103);
FORCEPROP 1 LAST CUSTOM_TXT_CDS <CON_PAGE_NUM> OF <CON_TOTAL_PAGES>
J 0
(-446 18);
DISPLAY 0.978723 (-446 18);
FORCEPROP 1 LAST Q_TITLE RETIMER_CPU1_P3 POWER(6)
J 0
(-9366 26);
DISPLAY 2.446809 (-9366 26);
PAINT GREEN (-9366 26);
FORCEPROP 2 LAST CDS_LIB pure_quanta
J 0
(0 0);
DISPLAY INVISIBLE (0 0);
FORCEPROP 1 LAST CDS_LMAN_SYM_OUTLINE -9475,6775,100,-125
J 0
(0 0);
DISPLAY 0.468085 (0 0);
PAINT GREEN (0 0);
DISPLAY INVISIBLE (0 0);
FORCEPROP 2 LAST PAGE_BORDER TRUE
J 0
(-7890 5250);
DISPLAY 0.638298 (-7890 5250);
PAINT PINK (-7890 5250);
DISPLAY INVISIBLE (-7890 5250);
FORCEPROP 2 LAST CDS_XR_PAGE_TITLE CR-355 : @T6G_MB_LIB.T6G(SCH_1):PAGE355
J 0
(-7890 5250);
DISPLAY 0.638298 (-7890 5250);
PAINT PINK (-7890 5250);
DISPLAY INVISIBLE (-7890 5250);
FORCEPROP 1 LAST Q_DEPT BU9
J 1
(-3763 49);
DISPLAY 1.957447 (-3763 49);
PAINT GREEN (-3763 49);
DISPLAY INVISIBLE (-3763 49);
FORCEPROP 1 LAST COMMENT_BODY TRUE
J 0
(12 -13);
DISPLAY 0.978723 (12 -13);
PAINT GREEN (12 -13);
DISPLAY INVISIBLE (12 -13);
FORCEADD DNS..2
(-8625 3950);
PAINT RED (-8625 3950);
FORCEPROP 2 LAST CDS_LIB mstr_misc
J 0
(-8625 3950);
DISPLAY INVISIBLE (-8625 3950);
FORCEPROP 1 LAST COMMENT_BODY TRUE
J 0
(-8625 3950);
DISPLAY INVISIBLE (-8625 3950);
WIRE 16 -1 (-1450 1175)(-1450 1025);
WIRE 16 -1 (-1300 1725)(-1300 1575);
WIRE 16 -1 (-8675 4100)(-8675 4025);
WIRE 16 -1 (-7650 3275)(-7650 3175);
WIRE 16 -1 (-7100 3675)(-7650 3675);
WIRE 16 -1 (-7650 3675)(-7650 3475);
WIRE 16 -1 (-7650 3675)(-8675 3675);
FORCEPROP 2 LAST SIG_NAME RT_CPU1_P3_VQPS
J 0
(-7860 3685);
DISPLAY 0.680851 (-7860 3685);
PAINT SKYBLUE (-7860 3685);
FORCEPROP 2 LASTPROP $XRERR UNIQUE?
J 0
(-8100 3685);
DISPLAY 0.638298 (-8100 3685);
PAINT MONO (-8100 3685);
DISPLAY INVISIBLE (-8100 3685);
WIRE 16 -1 (-8675 3825)(-8675 3675);
WIRE 16 -1 (-7100 4125)(-8350 4125);
WIRE 16 -1 (-8350 4375)(-8350 4125);
WIRE 16 -1 (-5625 3625)(-5625 3575);
WIRE 16 -1 (-5625 3675)(-5625 3625);
WIRE 16 -1 (-5950 3625)(-5625 3625);
WIRE 16 -1 (-5625 3575)(-5625 3525);
WIRE 16 -1 (-5950 3575)(-5625 3575);
WIRE 16 -1 (-5625 3525)(-5950 3525);
WIRE 16 -1 (-5625 3675)(-4650 3675);
WIRE 16 -1 (-5950 3675)(-5625 3675);
WIRE 16 -1 (-4650 3775)(-4650 3675);
WIRE 16 -1 (-5700 3925)(-5700 3875);
WIRE 16 -1 (-5700 3975)(-5700 3925);
WIRE 16 -1 (-5950 3925)(-5700 3925);
WIRE 16 -1 (-5700 3875)(-5700 3825);
WIRE 16 -1 (-5950 3875)(-5700 3875);
WIRE 16 -1 (-5700 3825)(-5950 3825);
WIRE 16 -1 (-5700 4025)(-5700 3975);
WIRE 16 -1 (-5950 3975)(-5700 3975);
WIRE 16 -1 (-5700 4075)(-5700 4025);
WIRE 16 -1 (-5950 4025)(-5700 4025);
WIRE 16 -1 (-5700 4125)(-5700 4075);
WIRE 16 -1 (-5950 4075)(-5700 4075);
WIRE 16 -1 (-5700 4175)(-5700 4125);
WIRE 16 -1 (-5950 4125)(-5700 4125);
WIRE 16 -1 (-5700 4225)(-5700 4175);
WIRE 16 -1 (-5950 4175)(-5700 4175);
WIRE 16 -1 (-5700 4275)(-5700 4225);
WIRE 16 -1 (-5950 4225)(-5700 4225);
WIRE 16 -1 (-5700 4275)(-4675 4275);
WIRE 16 -1 (-5700 4275)(-5950 4275);
WIRE 16 -1 (-4675 4775)(-4675 4275);
WIRE 16 -1 (-5725 4775)(-4675 4775);
WIRE 16 -1 (-4675 4775)(-4675 5000);
WIRE 16 -1 (-5950 4775)(-5725 4775);
WIRE 16 -1 (-5725 4775)(-5725 4725);
WIRE 16 -1 (-5725 4725)(-5725 4675);
WIRE 16 -1 (-5950 4725)(-5725 4725);
WIRE 16 -1 (-5725 4675)(-5725 4625);
WIRE 16 -1 (-5950 4675)(-5725 4675);
WIRE 16 -1 (-5950 4625)(-5725 4625);
WIRE 16 -1 (-5725 4625)(-5725 4575);
WIRE 16 -1 (-5725 4575)(-5725 4525);
WIRE 16 -1 (-5950 4575)(-5725 4575);
WIRE 16 -1 (-5725 4525)(-5950 4525);
WIRE 16 -1 (-5950 4475)(-5700 4475);
WIRE 16 -1 (-5700 4475)(-5250 4475);
WIRE 16 -1 (-5700 4475)(-5700 4425);
WIRE 16 -1 (-5700 4425)(-5700 4375);
WIRE 16 -1 (-5950 4425)(-5700 4425);
WIRE 16 -1 (-5250 4475)(-5250 4525);
WIRE 16 -1 (-5700 4375)(-5700 4325);
WIRE 16 -1 (-5700 4375)(-5950 4375);
WIRE 16 -1 (-5700 4325)(-5950 4325);
WIRE 16 -1 (-7100 4775)(-7525 4775);
WIRE 16 -1 (-7525 4775)(-7525 4725);
WIRE 16 -1 (-7525 4775)(-7775 4775);
WIRE 16 -1 (-7775 4775)(-7775 4825);
WIRE 16 -1 (-7100 4725)(-7525 4725);
WIRE 16 -1 (-7525 4725)(-7525 4675);
WIRE 16 -1 (-7100 4675)(-7525 4675);
WIRE 16 -1 (-7525 4675)(-7525 4625);
WIRE 16 -1 (-7100 4625)(-7525 4625);
WIRE 16 -1 (-7525 4625)(-7525 4575);
WIRE 16 -1 (-7525 4575)(-7100 4575);
WIRE 16 -1 (-1775 2250)(-1775 2200);
WIRE 16 -1 (-1775 2300)(-1775 2250);
WIRE 16 -1 (-1775 2250)(-1975 2250);
WIRE 16 -1 (-1775 2200)(-1775 2175);
WIRE 16 -1 (-1775 2200)(-1975 2200);
WIRE 16 -1 (-1775 2175)(-1075 2175);
WIRE 16 -1 (-1775 2350)(-1775 2300);
WIRE 16 -1 (-1775 2300)(-1975 2300);
WIRE 16 -1 (-1775 2400)(-1775 2350);
WIRE 16 -1 (-1775 2350)(-1975 2350);
WIRE 16 -1 (-1075 2175)(-1075 2125);
WIRE 16 -1 (-1775 2450)(-1775 2400);
WIRE 16 -1 (-1775 2400)(-1975 2400);
WIRE 16 -1 (-1775 2500)(-1775 2450);
WIRE 16 -1 (-1775 2450)(-1975 2450);
WIRE 16 -1 (-1775 2550)(-1775 2500);
WIRE 16 -1 (-1775 2500)(-1975 2500);
WIRE 16 -1 (-1775 2600)(-1775 2550);
WIRE 16 -1 (-1775 2550)(-1975 2550);
WIRE 16 -1 (-1775 2650)(-1775 2600);
WIRE 16 -1 (-1775 2600)(-1975 2600);
WIRE 16 -1 (-1775 2700)(-1775 2650);
WIRE 16 -1 (-1775 2650)(-1975 2650);
WIRE 16 -1 (-1775 2750)(-1775 2700);
WIRE 16 -1 (-1775 2700)(-1975 2700);
WIRE 16 -1 (-1775 2800)(-1775 2750);
WIRE 16 -1 (-1775 2750)(-1975 2750);
WIRE 16 -1 (-1775 2850)(-1775 2800);
WIRE 16 -1 (-1775 2800)(-1975 2800);
WIRE 16 -1 (-1775 2900)(-1775 2850);
WIRE 16 -1 (-1775 2850)(-1975 2850);
WIRE 16 -1 (-1775 2950)(-1775 2900);
WIRE 16 -1 (-1775 2900)(-1975 2900);
WIRE 16 -1 (-1775 3000)(-1775 2950);
WIRE 16 -1 (-1775 2950)(-1975 2950);
WIRE 16 -1 (-1775 3050)(-1775 3000);
WIRE 16 -1 (-1775 3000)(-1975 3000);
WIRE 16 -1 (-1775 3100)(-1775 3050);
WIRE 16 -1 (-1775 3050)(-1975 3050);
WIRE 16 -1 (-1775 3150)(-1775 3100);
WIRE 16 -1 (-1775 3100)(-1975 3100);
WIRE 16 -1 (-1775 3200)(-1775 3150);
WIRE 16 -1 (-1775 3150)(-1975 3150);
WIRE 16 -1 (-1775 3250)(-1775 3200);
WIRE 16 -1 (-1775 3200)(-1975 3200);
WIRE 16 -1 (-1775 3300)(-1775 3250);
WIRE 16 -1 (-1775 3250)(-1975 3250);
WIRE 16 -1 (-1775 3350)(-1775 3300);
WIRE 16 -1 (-1775 3300)(-1975 3300);
WIRE 16 -1 (-1775 3400)(-1775 3350);
WIRE 16 -1 (-1775 3350)(-1975 3350);
WIRE 16 -1 (-1775 3450)(-1775 3400);
WIRE 16 -1 (-1775 3400)(-1975 3400);
WIRE 16 -1 (-1775 3500)(-1775 3450);
WIRE 16 -1 (-1775 3450)(-1975 3450);
WIRE 16 -1 (-1775 3550)(-1775 3500);
WIRE 16 -1 (-1775 3500)(-1975 3500);
WIRE 16 -1 (-1775 3600)(-1775 3550);
WIRE 16 -1 (-1775 3550)(-1975 3550);
WIRE 16 -1 (-1775 3650)(-1775 3600);
WIRE 16 -1 (-1775 3600)(-1975 3600);
WIRE 16 -1 (-1775 3700)(-1775 3650);
WIRE 16 -1 (-1775 3650)(-1975 3650);
WIRE 16 -1 (-1775 3750)(-1775 3700);
WIRE 16 -1 (-1775 3700)(-1975 3700);
WIRE 16 -1 (-1775 3800)(-1775 3750);
WIRE 16 -1 (-1775 3750)(-1975 3750);
WIRE 16 -1 (-1775 3850)(-1775 3800);
WIRE 16 -1 (-1775 3800)(-1975 3800);
WIRE 16 -1 (-1775 3900)(-1775 3850);
WIRE 16 -1 (-1775 3850)(-1975 3850);
WIRE 16 -1 (-1775 3950)(-1775 3900);
WIRE 16 -1 (-1775 3900)(-1975 3900);
WIRE 16 -1 (-1775 4000)(-1775 3950);
WIRE 16 -1 (-1775 3950)(-1975 3950);
WIRE 16 -1 (-1775 4050)(-1775 4000);
WIRE 16 -1 (-1775 4000)(-1975 4000);
WIRE 16 -1 (-1775 4100)(-1775 4050);
WIRE 16 -1 (-1775 4050)(-1975 4050);
WIRE 16 -1 (-1775 4150)(-1775 4100);
WIRE 16 -1 (-1775 4100)(-1975 4100);
WIRE 16 -1 (-1775 4200)(-1775 4150);
WIRE 16 -1 (-1775 4150)(-1975 4150);
WIRE 16 -1 (-1775 4250)(-1775 4200);
WIRE 16 -1 (-1775 4200)(-1975 4200);
WIRE 16 -1 (-1775 4300)(-1775 4250);
WIRE 16 -1 (-1775 4250)(-1975 4250);
WIRE 16 -1 (-1775 4350)(-1775 4300);
WIRE 16 -1 (-1775 4300)(-1975 4300);
WIRE 16 -1 (-1775 4400)(-1775 4350);
WIRE 16 -1 (-1775 4350)(-1975 4350);
WIRE 16 -1 (-1775 4450)(-1775 4400);
WIRE 16 -1 (-1775 4400)(-1975 4400);
WIRE 16 -1 (-1775 4500)(-1775 4450);
WIRE 16 -1 (-1775 4450)(-1975 4450);
WIRE 16 -1 (-1775 4550)(-1775 4500);
WIRE 16 -1 (-1775 4500)(-1975 4500);
WIRE 16 -1 (-1775 4600)(-1775 4550);
WIRE 16 -1 (-1775 4550)(-1975 4550);
WIRE 16 -1 (-1775 4650)(-1775 4600);
WIRE 16 -1 (-1775 4600)(-1975 4600);
WIRE 16 -1 (-1775 4700)(-1775 4650);
WIRE 16 -1 (-1775 4650)(-1975 4650);
WIRE 16 -1 (-1775 4750)(-1775 4700);
WIRE 16 -1 (-1775 4700)(-1975 4700);
WIRE 16 -1 (-1775 4800)(-1775 4750);
WIRE 16 -1 (-1775 4750)(-1975 4750);
WIRE 16 -1 (-1775 4850)(-1775 4800);
WIRE 16 -1 (-1775 4800)(-1975 4800);
WIRE 16 -1 (-1775 4900)(-1775 4850);
WIRE 16 -1 (-1775 4850)(-1975 4850);
WIRE 16 -1 (-1775 4950)(-1775 4900);
WIRE 16 -1 (-1775 4900)(-1975 4900);
WIRE 16 -1 (-1775 5000)(-1775 4950);
WIRE 16 -1 (-1775 4950)(-1975 4950);
WIRE 16 -1 (-1775 5050)(-1775 5000);
WIRE 16 -1 (-1775 5000)(-1975 5000);
WIRE 16 -1 (-1775 5100)(-1775 5050);
WIRE 16 -1 (-1775 5050)(-1975 5050);
WIRE 16 -1 (-1775 5150)(-1775 5100);
WIRE 16 -1 (-1775 5100)(-1975 5100);
WIRE 16 -1 (-1775 5200)(-1775 5150);
WIRE 16 -1 (-1775 5150)(-1975 5150);
WIRE 16 -1 (-1775 5250)(-1775 5200);
WIRE 16 -1 (-1775 5200)(-1975 5200);
WIRE 16 -1 (-1775 5300)(-1775 5250);
WIRE 16 -1 (-1775 5250)(-1975 5250);
WIRE 16 -1 (-1775 5350)(-1775 5300);
WIRE 16 -1 (-1775 5300)(-1975 5300);
WIRE 16 -1 (-1775 5400)(-1775 5350);
WIRE 16 -1 (-1775 5350)(-1975 5350);
WIRE 16 -1 (-1775 5450)(-1775 5400);
WIRE 16 -1 (-1775 5400)(-1975 5400);
WIRE 16 -1 (-1775 5500)(-1775 5450);
WIRE 16 -1 (-1775 5450)(-1975 5450);
WIRE 16 -1 (-1775 5550)(-1775 5500);
WIRE 16 -1 (-1775 5500)(-1975 5500);
WIRE 16 -1 (-1775 5600)(-1775 5550);
WIRE 16 -1 (-1775 5550)(-1975 5550);
WIRE 16 -1 (-1775 5600)(-1975 5600);
WIRE 16 -1 (-1450 1600)(-1450 1550);
WIRE 16 -1 (-1450 1650)(-1450 1600);
WIRE 16 -1 (-1450 1600)(-1975 1600);
WIRE 16 -1 (-1450 1550)(-1450 1375);
WIRE 16 -1 (-1450 1550)(-1975 1550);
WIRE 16 -1 (-1450 1700)(-1450 1650);
WIRE 16 -1 (-1450 1650)(-1975 1650);
WIRE 16 -1 (-1450 1750)(-1450 1700);
WIRE 16 -1 (-1450 1700)(-1975 1700);
WIRE 16 -1 (-1450 1800)(-1450 1750);
WIRE 16 -1 (-1450 1750)(-1975 1750);
WIRE 16 -1 (-1450 1850)(-1450 1800);
WIRE 16 -1 (-1450 1800)(-1975 1800);
WIRE 16 -1 (-1450 1900)(-1450 1850);
WIRE 16 -1 (-1450 1850)(-1975 1850);
WIRE 16 -1 (-1450 1950)(-1450 1900);
WIRE 16 -1 (-1450 1900)(-1975 1900);
WIRE 16 -1 (-1450 2000)(-1450 1950);
WIRE 16 -1 (-1450 1950)(-1975 1950);
WIRE 16 -1 (-1450 2050)(-1450 2000);
WIRE 16 -1 (-1450 2000)(-1975 2000);
WIRE 16 -1 (-1450 2050)(-1975 2050);
FORCEPROP 2 LAST SIG_NAME NCF_CPU1_P3_GND
J 0
(-1860 2060);
DISPLAY 0.553191 (-1860 2060);
PAINT SKYBLUE (-1860 2060);
FORCEPROP 2 LASTPROP $XRERR UNIQUE?
J 0
(-2100 2060);
DISPLAY 0.638298 (-2100 2060);
PAINT MONO (-2100 2060);
DISPLAY INVISIBLE (-2100 2060);
WIRE 16 -1 (-1975 2100)(-1300 2100);
FORCEPROP 2 LAST SIG_NAME NCF_A1_CPU1_P3_GND
J 0
(-1810 2110);
DISPLAY 0.553191 (-1810 2110);
PAINT SKYBLUE (-1810 2110);
FORCEPROP 2 LASTPROP $XRERR UNIQUE?
J 0
(-2050 2110);
DISPLAY 0.638298 (-2050 2110);
PAINT MONO (-2050 2110);
DISPLAY INVISIBLE (-2050 2110);
WIRE 16 -1 (-1300 2100)(-1300 1925);
WIRE 16 -1 (-2925 1600)(-3125 1600);
WIRE 16 -1 (-3125 1650)(-3125 1600);
WIRE 16 -1 (-3125 1600)(-3125 1550);
WIRE 16 -1 (-2925 1550)(-3125 1550);
WIRE 16 -1 (-3125 1550)(-3125 1400);
WIRE 16 -1 (-2925 1650)(-3125 1650);
WIRE 16 -1 (-3125 1700)(-3125 1650);
WIRE 16 -1 (-2925 1700)(-3125 1700);
WIRE 16 -1 (-3125 1750)(-3125 1700);
WIRE 16 -1 (-2925 1750)(-3125 1750);
WIRE 16 -1 (-3125 1800)(-3125 1750);
WIRE 16 -1 (-2925 1800)(-3125 1800);
WIRE 16 -1 (-3125 1850)(-3125 1800);
WIRE 16 -1 (-2925 1850)(-3125 1850);
WIRE 16 -1 (-3125 1900)(-3125 1850);
WIRE 16 -1 (-2925 1900)(-3125 1900);
WIRE 16 -1 (-3125 1950)(-3125 1900);
WIRE 16 -1 (-2925 1950)(-3125 1950);
WIRE 16 -1 (-3125 2000)(-3125 1950);
WIRE 16 -1 (-3125 2050)(-3125 2000);
WIRE 16 -1 (-2925 2000)(-3125 2000);
WIRE 16 -1 (-2925 2050)(-3125 2050);
WIRE 16 -1 (-3125 2100)(-3125 2050);
WIRE 16 -1 (-2925 2100)(-3125 2100);
WIRE 16 -1 (-3125 2150)(-3125 2100);
WIRE 16 -1 (-2925 2150)(-3125 2150);
WIRE 16 -1 (-3125 2200)(-3125 2150);
WIRE 16 -1 (-2925 2200)(-3125 2200);
WIRE 16 -1 (-3125 2250)(-3125 2200);
WIRE 16 -1 (-2925 2250)(-3125 2250);
WIRE 16 -1 (-3125 2300)(-3125 2250);
WIRE 16 -1 (-2925 2300)(-3125 2300);
WIRE 16 -1 (-3125 2350)(-3125 2300);
WIRE 16 -1 (-2925 2350)(-3125 2350);
WIRE 16 -1 (-3125 2400)(-3125 2350);
WIRE 16 -1 (-2925 2400)(-3125 2400);
WIRE 16 -1 (-3125 2450)(-3125 2400);
WIRE 16 -1 (-2925 2450)(-3125 2450);
WIRE 16 -1 (-3125 2500)(-3125 2450);
WIRE 16 -1 (-2925 2500)(-3125 2500);
WIRE 16 -1 (-3125 2550)(-3125 2500);
WIRE 16 -1 (-2925 2550)(-3125 2550);
WIRE 16 -1 (-3125 2600)(-3125 2550);
WIRE 16 -1 (-2925 2600)(-3125 2600);
WIRE 16 -1 (-3125 2650)(-3125 2600);
WIRE 16 -1 (-2925 2650)(-3125 2650);
WIRE 16 -1 (-3125 2700)(-3125 2650);
WIRE 16 -1 (-2925 2700)(-3125 2700);
WIRE 16 -1 (-3125 2750)(-3125 2700);
WIRE 16 -1 (-2925 2750)(-3125 2750);
WIRE 16 -1 (-3125 2800)(-3125 2750);
WIRE 16 -1 (-2925 2800)(-3125 2800);
WIRE 16 -1 (-3125 2850)(-3125 2800);
WIRE 16 -1 (-2925 2850)(-3125 2850);
WIRE 16 -1 (-3125 2900)(-3125 2850);
WIRE 16 -1 (-2925 2900)(-3125 2900);
WIRE 16 -1 (-3125 2950)(-3125 2900);
WIRE 16 -1 (-2925 2950)(-3125 2950);
WIRE 16 -1 (-3125 3000)(-3125 2950);
WIRE 16 -1 (-2925 3000)(-3125 3000);
WIRE 16 -1 (-3125 3050)(-3125 3000);
WIRE 16 -1 (-2925 3050)(-3125 3050);
WIRE 16 -1 (-3125 3100)(-3125 3050);
WIRE 16 -1 (-2925 3100)(-3125 3100);
WIRE 16 -1 (-3125 3150)(-3125 3100);
WIRE 16 -1 (-2925 3150)(-3125 3150);
WIRE 16 -1 (-3125 3200)(-3125 3150);
WIRE 16 -1 (-2925 3200)(-3125 3200);
WIRE 16 -1 (-3125 3250)(-3125 3200);
WIRE 16 -1 (-2925 3250)(-3125 3250);
WIRE 16 -1 (-3125 3300)(-3125 3250);
WIRE 16 -1 (-2925 3300)(-3125 3300);
WIRE 16 -1 (-3125 3350)(-3125 3300);
WIRE 16 -1 (-2925 3350)(-3125 3350);
WIRE 16 -1 (-3125 3400)(-3125 3350);
WIRE 16 -1 (-2925 3400)(-3125 3400);
WIRE 16 -1 (-3125 3450)(-3125 3400);
WIRE 16 -1 (-2925 3450)(-3125 3450);
WIRE 16 -1 (-3125 3500)(-3125 3450);
WIRE 16 -1 (-2925 3500)(-3125 3500);
WIRE 16 -1 (-3125 3550)(-3125 3500);
WIRE 16 -1 (-2925 3550)(-3125 3550);
WIRE 16 -1 (-3125 3600)(-3125 3550);
WIRE 16 -1 (-2925 3600)(-3125 3600);
WIRE 16 -1 (-3125 3650)(-3125 3600);
WIRE 16 -1 (-2925 3650)(-3125 3650);
WIRE 16 -1 (-3125 3700)(-3125 3650);
WIRE 16 -1 (-2925 3700)(-3125 3700);
WIRE 16 -1 (-3125 3750)(-3125 3700);
WIRE 16 -1 (-2925 3750)(-3125 3750);
WIRE 16 -1 (-3125 3800)(-3125 3750);
WIRE 16 -1 (-2925 3800)(-3125 3800);
WIRE 16 -1 (-3125 3850)(-3125 3800);
WIRE 16 -1 (-2925 3850)(-3125 3850);
WIRE 16 -1 (-3125 3900)(-3125 3850);
WIRE 16 -1 (-2925 3900)(-3125 3900);
WIRE 16 -1 (-3125 3950)(-3125 3900);
WIRE 16 -1 (-2925 3950)(-3125 3950);
WIRE 16 -1 (-3125 4000)(-3125 3950);
WIRE 16 -1 (-2925 4000)(-3125 4000);
WIRE 16 -1 (-3125 4050)(-3125 4000);
WIRE 16 -1 (-3125 4100)(-3125 4050);
WIRE 16 -1 (-2925 4050)(-3125 4050);
WIRE 16 -1 (-2925 4100)(-3125 4100);
WIRE 16 -1 (-3125 4150)(-3125 4100);
WIRE 16 -1 (-2925 4150)(-3125 4150);
WIRE 16 -1 (-3125 4200)(-3125 4150);
WIRE 16 -1 (-2925 4200)(-3125 4200);
WIRE 16 -1 (-3125 4250)(-3125 4200);
WIRE 16 -1 (-2925 4250)(-3125 4250);
WIRE 16 -1 (-3125 4300)(-3125 4250);
WIRE 16 -1 (-2925 4300)(-3125 4300);
WIRE 16 -1 (-3125 4350)(-3125 4300);
WIRE 16 -1 (-2925 4350)(-3125 4350);
WIRE 16 -1 (-3125 4400)(-3125 4350);
WIRE 16 -1 (-2925 4400)(-3125 4400);
WIRE 16 -1 (-3125 4450)(-3125 4400);
WIRE 16 -1 (-2925 4450)(-3125 4450);
WIRE 16 -1 (-3125 4500)(-3125 4450);
WIRE 16 -1 (-2925 4500)(-3125 4500);
WIRE 16 -1 (-3125 4550)(-3125 4500);
WIRE 16 -1 (-2925 4550)(-3125 4550);
WIRE 16 -1 (-3125 4600)(-3125 4550);
WIRE 16 -1 (-2925 4600)(-3125 4600);
WIRE 16 -1 (-3125 4650)(-3125 4600);
WIRE 16 -1 (-2925 4650)(-3125 4650);
WIRE 16 -1 (-3125 4700)(-3125 4650);
WIRE 16 -1 (-2925 4700)(-3125 4700);
WIRE 16 -1 (-3125 4750)(-3125 4700);
WIRE 16 -1 (-2925 4750)(-3125 4750);
WIRE 16 -1 (-3125 4800)(-3125 4750);
WIRE 16 -1 (-2925 4800)(-3125 4800);
WIRE 16 -1 (-3125 4850)(-3125 4800);
WIRE 16 -1 (-2925 4850)(-3125 4850);
WIRE 16 -1 (-3125 4900)(-3125 4850);
WIRE 16 -1 (-2925 4900)(-3125 4900);
WIRE 16 -1 (-3125 4950)(-3125 4900);
WIRE 16 -1 (-2925 4950)(-3125 4950);
WIRE 16 -1 (-3125 5000)(-3125 4950);
WIRE 16 -1 (-2925 5000)(-3125 5000);
WIRE 16 -1 (-3125 5050)(-3125 5000);
WIRE 16 -1 (-2925 5050)(-3125 5050);
WIRE 16 -1 (-3125 5100)(-3125 5050);
WIRE 16 -1 (-2925 5100)(-3125 5100);
WIRE 16 -1 (-3125 5150)(-3125 5100);
WIRE 16 -1 (-2925 5150)(-3125 5150);
WIRE 16 -1 (-3125 5200)(-3125 5150);
WIRE 16 -1 (-2925 5200)(-3125 5200);
WIRE 16 -1 (-3125 5250)(-3125 5200);
WIRE 16 -1 (-2925 5250)(-3125 5250);
WIRE 16 -1 (-3125 5300)(-3125 5250);
WIRE 16 -1 (-2925 5300)(-3125 5300);
WIRE 16 -1 (-3125 5350)(-3125 5300);
WIRE 16 -1 (-2925 5350)(-3125 5350);
WIRE 16 -1 (-3125 5400)(-3125 5350);
WIRE 16 -1 (-2925 5400)(-3125 5400);
WIRE 16 -1 (-3125 5450)(-3125 5400);
WIRE 16 -1 (-2925 5450)(-3125 5450);
WIRE 16 -1 (-3125 5500)(-3125 5450);
WIRE 16 -1 (-2925 5500)(-3125 5500);
WIRE 16 -1 (-3125 5550)(-3125 5500);
WIRE 16 -1 (-2925 5550)(-3125 5550);
WIRE 16 -1 (-3125 5600)(-3125 5550);
WIRE 16 -1 (-2925 5600)(-3125 5600);
DOT 1 (-7650 3675);
DOT 1 (-1450 1850);
DOT 1 (-1450 1950);
DOT 1 (-5700 4125);
DOT 1 (-3125 4650);
DOT 1 (-1775 5550);
DOT 1 (-1775 5500);
DOT 1 (-1775 5350);
DOT 1 (-1775 5450);
DOT 1 (-1775 5400);
DOT 1 (-1775 5250);
DOT 1 (-1775 5300);
DOT 1 (-1775 5200);
DOT 1 (-1775 5150);
DOT 1 (-1775 5100);
DOT 1 (-1775 5000);
DOT 1 (-1775 5050);
DOT 1 (-1775 4950);
DOT 1 (-1775 4900);
DOT 1 (-1775 4850);
DOT 1 (-1775 4700);
DOT 1 (-1775 4750);
DOT 1 (-1775 4800);
DOT 1 (-1775 4650);
DOT 1 (-1775 4600);
DOT 1 (-1775 4450);
DOT 1 (-1775 4500);
DOT 1 (-1775 4550);
DOT 1 (-1775 4350);
DOT 1 (-1775 4400);
DOT 1 (-1775 4300);
DOT 1 (-1775 4250);
DOT 1 (-1775 4200);
DOT 1 (-1775 4100);
DOT 1 (-1775 4150);
DOT 1 (-1775 4050);
DOT 1 (-1775 4000);
DOT 1 (-1775 3950);
DOT 1 (-1775 3900);
DOT 1 (-3125 5550);
DOT 1 (-3125 5450);
DOT 1 (-3125 5500);
DOT 1 (-3125 5350);
DOT 1 (-3125 5400);
DOT 1 (-3125 5200);
DOT 1 (-3125 5100);
DOT 1 (-3125 5050);
DOT 1 (-3125 5150);
DOT 1 (-3125 4950);
DOT 1 (-3125 5000);
DOT 1 (-3125 4900);
DOT 1 (-3125 4850);
DOT 1 (-3125 4800);
DOT 1 (-3125 4700);
DOT 1 (-3125 4750);
DOT 1 (-3125 4550);
DOT 1 (-3125 4600);
DOT 1 (-3125 4450);
DOT 1 (-3125 4400);
DOT 1 (-3125 4500);
DOT 1 (-3125 4300);
DOT 1 (-3125 4350);
DOT 1 (-3125 4150);
DOT 1 (-3125 4200);
DOT 1 (-3125 4250);
DOT 1 (-3125 4050);
DOT 1 (-3125 4100);
DOT 1 (-3125 4000);
DOT 1 (-3125 3900);
DOT 1 (-3125 3950);
DOT 1 (-1775 3400);
DOT 1 (-1775 3850);
DOT 1 (-1775 3800);
DOT 1 (-1775 3750);
DOT 1 (-1775 3700);
DOT 1 (-1775 3550);
DOT 1 (-1775 3600);
DOT 1 (-1775 3650);
DOT 1 (-1775 3500);
DOT 1 (-1775 3450);
DOT 1 (-1775 3300);
DOT 1 (-1775 3350);
DOT 1 (-1775 3250);
DOT 1 (-1775 3100);
DOT 1 (-1775 3050);
DOT 1 (-1775 2950);
DOT 1 (-1775 3000);
DOT 1 (-1775 2900);
DOT 1 (-1775 2850);
DOT 1 (-1450 2000);
DOT 1 (-1450 1900);
DOT 1 (-1775 2450);
DOT 1 (-1775 2300);
DOT 1 (-1775 2400);
DOT 1 (-1775 2800);
DOT 1 (-1775 2650);
DOT 1 (-1775 2700);
DOT 1 (-1775 2750);
DOT 1 (-1775 2600);
DOT 1 (-1775 2550);
DOT 1 (-1775 2500);
DOT 1 (-1775 2350);
DOT 1 (-1775 2200);
DOT 1 (-1775 2250);
DOT 1 (-1450 1800);
DOT 1 (-1450 1750);
DOT 1 (-1450 1600);
DOT 1 (-1450 1650);
DOT 1 (-1450 1550);
DOT 1 (-3125 3800);
DOT 1 (-3125 3850);
DOT 1 (-3125 3750);
DOT 1 (-3125 3700);
DOT 1 (-3125 3650);
DOT 1 (-3125 3550);
DOT 1 (-3125 3600);
DOT 1 (-3125 3500);
DOT 1 (-3125 3400);
DOT 1 (-3125 3450);
DOT 1 (-3125 3300);
DOT 1 (-3125 3250);
DOT 1 (-3125 3350);
DOT 1 (-3125 3200);
DOT 1 (-3125 3150);
DOT 1 (-3125 3050);
DOT 1 (-3125 3000);
DOT 1 (-3125 3100);
DOT 1 (-3125 2900);
DOT 1 (-3125 2950);
DOT 1 (-3125 2850);
DOT 1 (-3125 2800);
DOT 1 (-3125 2650);
DOT 1 (-3125 2700);
DOT 1 (-3125 2600);
DOT 1 (-3125 2500);
DOT 1 (-3125 2550);
DOT 1 (-3125 2350);
DOT 1 (-3125 2450);
DOT 1 (-3125 2400);
DOT 1 (-3125 2250);
DOT 1 (-3125 2300);
DOT 1 (-3125 2100);
DOT 1 (-3125 2150);
DOT 1 (-3125 2000);
DOT 1 (-3125 2050);
DOT 1 (-3125 1900);
DOT 1 (-3125 1850);
DOT 1 (-3125 1950);
DOT 1 (-3125 1750);
DOT 1 (-3125 1800);
DOT 1 (-3125 1700);
DOT 1 (-3125 1650);
DOT 1 (-3125 1600);
DOT 1 (-3125 1550);
DOT 1 (-4675 4775);
DOT 1 (-5725 4775);
DOT 1 (-5725 4725);
DOT 1 (-5725 4675);
DOT 1 (-5725 4575);
DOT 1 (-5700 4475);
DOT 1 (-5700 4425);
DOT 1 (-5700 4375);
DOT 1 (-5700 4175);
DOT 1 (-5700 4225);
DOT 1 (-5700 3925);
DOT 1 (-5700 3975);
DOT 1 (-7525 4725);
DOT 1 (-5700 3875);
DOT 1 (-5625 3675);
DOT 1 (-5625 3625);
DOT 1 (-3125 5300);
DOT 1 (-3125 5250);
DOT 1 (-7525 4625);
DOT 1 (-7525 4675);
DOT 1 (-5700 4275);
DOT 1 (-3125 2750);
DOT 1 (-3125 2200);
DOT 1 (-1775 3150);
DOT 1 (-1775 3200);
DOT 1 (-1450 1700);
DOT 1 (-7525 4775);
DOT 1 (-5725 4625);
DOT 1 (-5700 4075);
DOT 1 (-5700 4025);
DOT 1 (-5625 3575);
QUIT
